# S9S_MB_2U (Grand Teton) — schematic netlist excerpt (pin names and nets, part order shuffled) for the footprints in the layout excerpt that follows; sources: Cadence DE-HDL packaged netlist, KiCad conversion of 03242023_DA0F0TMBIJ0_F0T_Motherboard_J_brd_V01_OCP.brd

R1335  Q_RES  1K 1% CHIP  pkg 0402LF  page 201 : A = GND ; B = PD_PASSWORD_CLEAR
C738  Q_CAP_DIFFBUS  DIFF BUS_0.22UF 6.3V 20% X6S  pkg C0201  page 176 : \1\ = P5E_CPU1_PE0_TX_C_DN<1> ; \2\ = P5E_CPU1_PE0_TX_DN<1>
R4483  Q_RES  49.9 1% EMPTY  pkg 0402LF  page 152 : A = USB2_HOST_BMC_B_BUF_DN ; B = GND

(kicad_pcb
	(version 20260206)
	(generator "pcbnew")
	(generator_version "10.0")
	(general
		(thickness 1.6)
		(legacy_teardrops no)
	)
	(paper "A4")
	(title_block
		(title "03242023_DA0F0TMBIJ0_F0T_Motherboard_J_brd_V01_OCP.brd")
		(comment 1 "Grand Teton / footprints 67-69 of 6105")
	)
	(layers
		(0 "F.Cu" signal "TOP")
		(4 "In1.Cu" signal "GND")
		(6 "In2.Cu" signal "IN1")
		(8 "In3.Cu" signal "GND1")
		(10 "In4.Cu" signal "IN2")
		(12 "In5.Cu" signal "GND2")
		(14 "In6.Cu" signal "IN3")
		(16 "In7.Cu" signal "GND3")
		(18 "In8.Cu" signal "VCC")
		(20 "In9.Cu" signal "VCC1")
		(22 "In10.Cu" signal "GND4")
		(24 "In11.Cu" signal "IN4")
		(26 "In12.Cu" signal "GND5")
		(28 "In13.Cu" signal "IN5")
		(30 "In14.Cu" signal "GND6")
		(32 "In15.Cu" signal "IN6")
		(34 "In16.Cu" signal "GND7")
		(2 "B.Cu" signal "BOTTOM")
		(9 "F.Adhes" user "F.Adhesive")
		(11 "B.Adhes" user "B.Adhesive")
		(13 "F.Paste" user "Package Geometry/Pastemask Top")
		(15 "B.Paste" user "Package Geometry/Pastemask Bottom")
		(5 "F.SilkS" user "Ref Des/Silkscreen Top")
		(7 "B.SilkS" user "Ref Des/Silkscreen Bottom")
		(1 "F.Mask" user "Board Geometry/Soldermask Top")
		(3 "B.Mask" user "Board Geometry/Soldermask Bottom")
		(17 "Dwgs.User" user "User.Drawings")
		(19 "Cmts.User" user "User.Comments")
		(21 "Eco1.User" user "User.Eco1")
		(23 "Eco2.User" user "User.Eco2")
		(25 "Edge.Cuts" user "Board Geometry/Outline")
		(27 "Margin" user)
		(31 "F.CrtYd" user "Package Geometry/Place Bound Top")
		(29 "B.CrtYd" user "Package Geometry/Place Bound Bottom")
		(35 "F.Fab" user "Ref Des/Assembly Top")
		(33 "B.Fab" user "Ref Des/Assembly Bottom")
	)
	(footprint ""
		(layer "F.Cu")
		(at 413.520382 -29.877258)
		(property "Reference" "R1335"
			(at 0 0 0)
			(layer "F.SilkS")
			(hide yes)
			(effects
				(font
					(size 1.27 1.27)
				)
			)
		)
		(property "Value" ""
			(at 0 0 0)
			(layer "F.Fab")
			(effects
				(font
					(size 1.27 1.27)
				)
			)
		)
		(duplicate_pad_numbers_are_jumpers no)
		(fp_line
			(start -0.7874 -0.4064)
			(end 0.7874 -0.4064)
			(stroke
				(width 0.1524)
				(type default)
			)
			(layer "F.SilkS")
		)
		(fp_line
			(start -0.7874 0.4064)
			(end -0.7874 -0.4064)
			(stroke
				(width 0.1524)
				(type default)
			)
			(layer "F.SilkS")
		)
		(fp_line
			(start 0.7874 -0.4064)
			(end 0.7874 0.4064)
			(stroke
				(width 0.1524)
				(type default)
			)
			(layer "F.SilkS")
		)
		(fp_line
			(start 0.7874 0.4064)
			(end -0.7874 0.4064)
			(stroke
				(width 0.1524)
				(type default)
			)
			(layer "F.SilkS")
		)
		(fp_line
			(start -0.67945 -0.305054)
			(end -0.12065 -0.305054)
			(stroke
				(width 0.1)
				(type default)
			)
			(layer "F.Fab")
		)
		(fp_line
			(start -0.67945 0.3048)
			(end -0.67945 -0.305054)
			(stroke
				(width 0.1)
				(type default)
			)
			(layer "F.Fab")
		)
		(fp_line
			(start -0.12065 -0.305054)
			(end -0.12065 -0.2794)
			(stroke
				(width 0.1)
				(type default)
			)
			(layer "F.Fab")
		)
		(fp_line
			(start -0.12065 -0.2794)
			(end 0.12065 -0.2794)
			(stroke
				(width 0.1)
				(type default)
			)
			(layer "F.Fab")
		)
		(fp_line
			(start -0.12065 0.2794)
			(end -0.12065 0.3048)
			(stroke
				(width 0.1)
				(type default)
			)
			(layer "F.Fab")
		)
		(fp_line
			(start -0.12065 0.3048)
			(end -0.67945 0.3048)
			(stroke
				(width 0.1)
				(type default)
			)
			(layer "F.Fab")
		)
		(fp_line
			(start 0.120396 0.2794)
			(end -0.12065 0.2794)
			(stroke
				(width 0.1)
				(type default)
			)
			(layer "F.Fab")
		)
		(fp_line
			(start 0.120396 0.3048)
			(end 0.120396 0.2794)
			(stroke
				(width 0.1)
				(type default)
			)
			(layer "F.Fab")
		)
		(fp_line
			(start 0.12065 -0.3048)
			(end 0.67945 -0.3048)
			(stroke
				(width 0.1)
				(type default)
			)
			(layer "F.Fab")
		)
		(fp_line
			(start 0.12065 -0.2794)
			(end 0.12065 -0.3048)
			(stroke
				(width 0.1)
				(type default)
			)
			(layer "F.Fab")
		)
		(fp_line
			(start 0.67945 -0.3048)
			(end 0.67945 0.3048)
			(stroke
				(width 0.1)
				(type default)
			)
			(layer "F.Fab")
		)
		(fp_line
			(start 0.67945 0.3048)
			(end 0.120396 0.3048)
			(stroke
				(width 0.1)
				(type default)
			)
			(layer "F.Fab")
		)
		(pad "1" smd circle
			(at -0.40005 0)
			(size 0 0)
			(layers "F.Cu" "F.Mask" "F.Paste")
			(net "GND")
		)
		(pad "2" smd circle
			(at 0.40005 0)
			(size 0 0)
			(layers "F.Cu" "F.Mask" "F.Paste")
			(net "PD_PASSWORD_CLEAR")
		)
	)
	(footprint ""
		(layer "F.Cu")
		(at 90.839798 -402.371052 -90)
		(property "Reference" "C738"
			(at 0 0 270)
			(layer "F.SilkS")
			(hide yes)
			(effects
				(font
					(size 1.27 1.27)
				)
			)
		)
		(property "Value" ""
			(at 0 0 270)
			(layer "F.Fab")
			(effects
				(font
					(size 1.27 1.27)
				)
			)
		)
		(duplicate_pad_numbers_are_jumpers no)
		(fp_line
			(start -0.299974 0.150114)
			(end -0.299974 -0.150114)
			(stroke
				(width 0.1)
				(type default)
			)
			(layer "F.Fab")
		)
		(fp_line
			(start 0.299974 0.150114)
			(end -0.299974 0.150114)
			(stroke
				(width 0.1)
				(type default)
			)
			(layer "F.Fab")
		)
		(fp_line
			(start -0.299974 -0.150114)
			(end 0.299974 -0.150114)
			(stroke
				(width 0.1)
				(type default)
			)
			(layer "F.Fab")
		)
		(fp_line
			(start 0.299974 -0.150114)
			(end 0.299974 0.150114)
			(stroke
				(width 0.1)
				(type default)
			)
			(layer "F.Fab")
		)
		(pad "1" smd rect
			(at -0.2667 0 270)
			(size 0.3048 0.381)
			(layers "F.Cu" "F.Mask" "F.Paste")
			(net "P5E_CPU1_PE0_TX_C_DN<1>")
		)
		(pad "2" smd rect
			(at 0.2667 0 270)
			(size 0.3048 0.381)
			(layers "F.Cu" "F.Mask" "F.Paste")
			(net "P5E_CPU1_PE0_TX_DN<1>")
		)
	)
	(footprint ""
		(layer "F.Cu")
		(at 17.045432 -107.123484)
		(property "Reference" "R4483"
			(at 0 0 0)
			(layer "F.SilkS")
			(hide yes)
			(effects
				(font
					(size 1.27 1.27)
				)
			)
		)
		(property "Value" ""
			(at 0 0 0)
			(layer "F.Fab")
			(effects
				(font
					(size 1.27 1.27)
				)
			)
		)
		(duplicate_pad_numbers_are_jumpers no)
		(fp_line
			(start 0.015748 -0.4064)
			(end 0.7874 -0.4064)
			(stroke
				(width 0.1524)
				(type default)
			)
			(layer "F.SilkS")
		)
		(fp_line
			(start 0.7874 -0.4064)
			(end 0.7874 0.4064)
			(stroke
				(width 0.1524)
				(type default)
			)
			(layer "F.SilkS")
		)
		(fp_line
			(start 0.7874 0.4064)
			(end 0.028448 0.4064)
			(stroke
				(width 0.1524)
				(type default)
			)
			(layer "F.SilkS")
		)
		(fp_line
			(start -0.67945 -0.305054)
			(end -0.12065 -0.305054)
			(stroke
				(width 0.1)
				(type default)
			)
			(layer "F.Fab")
		)
		(fp_line
			(start -0.67945 0.3048)
			(end -0.67945 -0.305054)
			(stroke
				(width 0.1)
				(type default)
			)
			(layer "F.Fab")
		)
		(fp_line
			(start -0.12065 -0.305054)
			(end -0.12065 -0.2794)
			(stroke
				(width 0.1)
				(type default)
			)
			(layer "F.Fab")
		)
		(fp_line
			(start -0.12065 -0.2794)
			(end 0.12065 -0.2794)
			(stroke
				(width 0.1)
				(type default)
			)
			(layer "F.Fab")
		)
		(fp_line
			(start -0.12065 0.2794)
			(end -0.12065 0.3048)
			(stroke
				(width 0.1)
				(type default)
			)
			(layer "F.Fab")
		)
		(fp_line
			(start -0.12065 0.3048)
			(end -0.67945 0.3048)
			(stroke
				(width 0.1)
				(type default)
			)
			(layer "F.Fab")
		)
		(fp_line
			(start 0.120396 0.2794)
			(end -0.12065 0.2794)
			(stroke
				(width 0.1)
				(type default)
			)
			(layer "F.Fab")
		)
		(fp_line
			(start 0.120396 0.3048)
			(end 0.120396 0.2794)
			(stroke
				(width 0.1)
				(type default)
			)
			(layer "F.Fab")
		)
		(fp_line
			(start 0.12065 -0.3048)
			(end 0.67945 -0.3048)
			(stroke
				(width 0.1)
				(type default)
			)
			(layer "F.Fab")
		)
		(fp_line
			(start 0.12065 -0.2794)
			(end 0.12065 -0.3048)
			(stroke
				(width 0.1)
				(type default)
			)
			(layer "F.Fab")
		)
		(fp_line
			(start 0.67945 -0.3048)
			(end 0.67945 0.3048)
			(stroke
				(width 0.1)
				(type default)
			)
			(layer "F.Fab")
		)
		(fp_line
			(start 0.67945 0.3048)
			(end 0.120396 0.3048)
			(stroke
				(width 0.1)
				(type default)
			)
			(layer "F.Fab")
		)
		(pad "1" smd circle
			(at -0.40005 0)
			(size 0 0)
			(layers "F.Cu" "F.Mask" "F.Paste")
			(net "USB2_HOST_BMC_B_BUF_DN")
		)
		(pad "2" smd circle
			(at 0.40005 0)
			(size 0 0)
			(layers "F.Cu" "F.Mask" "F.Paste")
			(net "GND")
		)
	)
)
